(kicad_pcb
	(version 20260206)
	(generator "pcbnew")
	(generator_version "10.0")
	(general
		(thickness 1.6)
		(legacy_teardrops no)
	)
	(paper "A4")
	(title_block
		(title "peb — Lightning_PEB_BRD.brd")
		(comment 1 "Lightning (Wiwynn / Facebook NVMe JBOF) / footprints 1460-1466 of 2563")
	)
	(layers
		(0 "F.Cu" signal "TOP")
		(4 "In1.Cu" signal "L2GND")
		(6 "In2.Cu" signal "L3")
		(8 "In3.Cu" signal "L4VCC")
		(10 "In4.Cu" signal "L5VCC")
		(12 "In5.Cu" signal "L6")
		(14 "In6.Cu" signal "L7GND")
		(2 "B.Cu" signal "BOTTOM")
		(9 "F.Adhes" user "F.Adhesive")
		(11 "B.Adhes" user "B.Adhesive")
		(13 "F.Paste" user "Package Geometry/Pastemask Top")
		(15 "B.Paste" user "Package Geometry/Pastemask Bottom")
		(5 "F.SilkS" user "Ref Des/Silkscreen Top")
		(7 "B.SilkS" user "Ref Des/Silkscreen Bottom")
		(1 "F.Mask" user "Board Geometry/Soldermask Top")
		(3 "B.Mask" user "Board Geometry/Soldermask Bottom")
		(17 "Dwgs.User" user "User.Drawings")
		(19 "Cmts.User" user "User.Comments")
		(21 "Eco1.User" user "User.Eco1")
		(23 "Eco2.User" user "User.Eco2")
		(25 "Edge.Cuts" user "Board Geometry/Outline")
		(27 "Margin" user)
		(31 "F.CrtYd" user "Package Geometry/Place Bound Top")
		(29 "B.CrtYd" user "Package Geometry/Place Bound Bottom")
		(35 "F.Fab" user "Ref Des/Assembly Top")
		(33 "B.Fab" user "Ref Des/Assembly Bottom")
	)
	(footprint ""
		(layer "F.Cu")
		(at 330.581 -99.568 180)
		(property "Reference" "R4164"
			(at 0 0 180)
			(layer "F.SilkS")
			(hide yes)
			(effects
				(font
					(size 1.27 1.27)
				)
			)
		)
		(property "Value" "4K7R2F-GP"
			(at 0.064008 -3.993896 180)
			(unlocked yes)
			(layer "F.Fab")
			(hide yes)
			(effects
				(font
					(size 1.016 1.016)
					(thickness 0.1524)
				)
			)
		)
		(property "Device Type" "R402H16"
			(at 0.064008 -5.517896 180)
			(unlocked yes)
			(layer "F.Fab")
			(hide yes)
			(effects
				(font
					(size 1.016 1.016)
					(thickness 0.1524)
				)
			)
		)
		(duplicate_pad_numbers_are_jumpers no)
		(fp_line
			(start 0.508 -0.9398)
			(end -0.508 -0.9398)
			(stroke
				(width 0.1524)
				(type default)
			)
			(layer "F.SilkS")
		)
		(fp_line
			(start -0.508 -0.9398)
			(end -0.508 0.9398)
			(stroke
				(width 0.1524)
				(type default)
			)
			(layer "F.SilkS")
		)
		(fp_rect
			(start -0.508 0.9398)
			(end 0.508 -0.9398)
			(stroke
				(width 0)
				(type default)
			)
			(fill no)
			(layer "F.CrtYd")
		)
		(fp_rect
			(start -0.508 0.9398)
			(end 0.508 -0.9398)
			(stroke
				(width 0)
				(type default)
			)
			(fill no)
			(layer "F.Fab")
		)
		(pad "1" smd custom
			(at 0 -0.4445 180)
			(size 0.1397 0.1397)
			(layers "F.Cu" "F.Mask" "F.Paste")
			(net "VS2_LED")
			(options
				(clearance outline)
				(anchor circle)
			)
			(primitives
				(gr_poly
					(pts
						(arc
							(start -0.1778 -0.2794)
							(mid -0.249642 -0.249642)
							(end -0.2794 -0.1778)
						)
						(arc
							(start -0.2794 0.1778)
							(mid -0.249642 0.249642)
							(end -0.1778 0.2794)
						)
						(arc
							(start 0.1778 0.2794)
							(mid 0.249642 0.249642)
							(end 0.2794 0.1778)
						)
						(arc
							(start 0.2794 -0.1778)
							(mid 0.249642 -0.249642)
							(end 0.1778 -0.2794)
						)
					)
					(width 0)
					(fill yes)
				)
			)
		)
		(pad "2" smd custom
			(at 0 0.4445 180)
			(size 0.1397 0.1397)
			(layers "F.Cu" "F.Mask" "F.Paste")
			(net "P3V3_STBY")
			(options
				(clearance outline)
				(anchor circle)
			)
			(primitives
				(gr_poly
					(pts
						(arc
							(start -0.1778 -0.2794)
							(mid -0.249642 -0.249642)
							(end -0.2794 -0.1778)
						)
						(arc
							(start -0.2794 0.1778)
							(mid -0.249642 0.249642)
							(end -0.1778 0.2794)
						)
						(arc
							(start 0.1778 0.2794)
							(mid 0.249642 0.249642)
							(end 0.2794 0.1778)
						)
						(arc
							(start 0.2794 -0.1778)
							(mid 0.249642 -0.249642)
							(end 0.1778 -0.2794)
						)
					)
					(width 0)
					(fill yes)
				)
			)
		)
	)
	(footprint ""
		(layer "F.Cu")
		(at 123.17984 -3.34772 90)
		(property "Reference" "SR711"
			(at 0 0 90)
			(layer "F.SilkS")
			(hide yes)
			(effects
				(font
					(size 1.27 1.27)
				)
			)
		)
		(property "Value" "150R2F-1-GP"
			(at 0.064008 -3.993896 90)
			(unlocked yes)
			(layer "F.Fab")
			(hide yes)
			(effects
				(font
					(size 1.016 1.016)
					(thickness 0.1524)
				)
			)
		)
		(property "Device Type" "R402H16"
			(at 0.064008 -5.517896 90)
			(unlocked yes)
			(layer "F.Fab")
			(hide yes)
			(effects
				(font
					(size 1.016 1.016)
					(thickness 0.1524)
				)
			)
		)
		(duplicate_pad_numbers_are_jumpers no)
		(fp_line
			(start 0.508 -0.9398)
			(end -0.508 -0.9398)
			(stroke
				(width 0.1524)
				(type default)
			)
			(layer "F.SilkS")
		)
		(fp_line
			(start -0.508 -0.9398)
			(end -0.508 0.9398)
			(stroke
				(width 0.1524)
				(type default)
			)
			(layer "F.SilkS")
		)
		(fp_rect
			(start -0.508 0.9398)
			(end 0.508 -0.9398)
			(stroke
				(width 0)
				(type default)
			)
			(fill no)
			(layer "F.CrtYd")
		)
		(fp_rect
			(start -0.508 0.9398)
			(end 0.508 -0.9398)
			(stroke
				(width 0)
				(type default)
			)
			(fill no)
			(layer "F.Fab")
		)
		(pad "1" smd custom
			(at 0 -0.4445 90)
			(size 0.1397 0.1397)
			(layers "F.Cu" "F.Mask" "F.Paste")
			(net "P3V3_STBY")
			(options
				(clearance outline)
				(anchor circle)
			)
			(primitives
				(gr_poly
					(pts
						(arc
							(start -0.1778 -0.2794)
							(mid -0.249642 -0.249642)
							(end -0.2794 -0.1778)
						)
						(arc
							(start -0.2794 0.1778)
							(mid -0.249642 0.249642)
							(end -0.1778 0.2794)
						)
						(arc
							(start 0.1778 0.2794)
							(mid 0.249642 0.249642)
							(end 0.2794 0.1778)
						)
						(arc
							(start 0.2794 -0.1778)
							(mid 0.249642 -0.249642)
							(end 0.1778 -0.2794)
						)
					)
					(width 0)
					(fill yes)
				)
			)
		)
		(pad "2" smd custom
			(at 0 0.4445 90)
			(size 0.1397 0.1397)
			(layers "F.Cu" "F.Mask" "F.Paste")
			(net "LED_R_4")
			(options
				(clearance outline)
				(anchor circle)
			)
			(primitives
				(gr_poly
					(pts
						(arc
							(start -0.1778 -0.2794)
							(mid -0.249642 -0.249642)
							(end -0.2794 -0.1778)
						)
						(arc
							(start -0.2794 0.1778)
							(mid -0.249642 0.249642)
							(end -0.1778 0.2794)
						)
						(arc
							(start 0.1778 0.2794)
							(mid 0.249642 0.249642)
							(end 0.2794 0.1778)
						)
						(arc
							(start 0.2794 -0.1778)
							(mid 0.249642 -0.249642)
							(end 0.1778 -0.2794)
						)
					)
					(width 0)
					(fill yes)
				)
			)
		)
	)
	(footprint ""
		(layer "F.Cu")
		(at 20.955 -136.7282 90)
		(property "Reference" "R290"
			(at 0 0 90)
			(layer "F.SilkS")
			(hide yes)
			(effects
				(font
					(size 1.27 1.27)
				)
			)
		)
		(property "Value" "0R2J-2-GP"
			(at 0.064008 -3.993896 90)
			(unlocked yes)
			(layer "F.Fab")
			(hide yes)
			(effects
				(font
					(size 1.016 1.016)
					(thickness 0.1524)
				)
			)
		)
		(property "Device Type" "R402H16"
			(at 0.064008 -5.517896 90)
			(unlocked yes)
			(layer "F.Fab")
			(hide yes)
			(effects
				(font
					(size 1.016 1.016)
					(thickness 0.1524)
				)
			)
		)
		(duplicate_pad_numbers_are_jumpers no)
		(fp_line
			(start 0.508 -0.9398)
			(end -0.508 -0.9398)
			(stroke
				(width 0.1524)
				(type default)
			)
			(layer "F.SilkS")
		)
		(fp_line
			(start -0.508 -0.9398)
			(end -0.508 0.9398)
			(stroke
				(width 0.1524)
				(type default)
			)
			(layer "F.SilkS")
		)
		(fp_rect
			(start -0.508 0.9398)
			(end 0.508 -0.9398)
			(stroke
				(width 0)
				(type default)
			)
			(fill no)
			(layer "F.CrtYd")
		)
		(fp_rect
			(start -0.508 0.9398)
			(end 0.508 -0.9398)
			(stroke
				(width 0)
				(type default)
			)
			(fill no)
			(layer "F.Fab")
		)
		(pad "1" smd custom
			(at 0 -0.4445 90)
			(size 0.1397 0.1397)
			(layers "F.Cu" "F.Mask" "F.Paste")
			(net "TRAY_POWER_CRIT_N")
			(options
				(clearance outline)
				(anchor circle)
			)
			(primitives
				(gr_poly
					(pts
						(arc
							(start -0.1778 -0.2794)
							(mid -0.249642 -0.249642)
							(end -0.2794 -0.1778)
						)
						(arc
							(start -0.2794 0.1778)
							(mid -0.249642 0.249642)
							(end -0.1778 0.2794)
						)
						(arc
							(start 0.1778 0.2794)
							(mid 0.249642 0.249642)
							(end 0.2794 0.1778)
						)
						(arc
							(start 0.2794 -0.1778)
							(mid 0.249642 -0.249642)
							(end 0.1778 -0.2794)
						)
					)
					(width 0)
					(fill yes)
				)
			)
		)
		(pad "2" smd custom
			(at 0 0.4445 90)
			(size 0.1397 0.1397)
			(layers "F.Cu" "F.Mask" "F.Paste")
			(net "GPIOR5_R")
			(options
				(clearance outline)
				(anchor circle)
			)
			(primitives
				(gr_poly
					(pts
						(arc
							(start -0.1778 -0.2794)
							(mid -0.249642 -0.249642)
							(end -0.2794 -0.1778)
						)
						(arc
							(start -0.2794 0.1778)
							(mid -0.249642 0.249642)
							(end -0.1778 0.2794)
						)
						(arc
							(start 0.1778 0.2794)
							(mid 0.249642 0.249642)
							(end 0.2794 0.1778)
						)
						(arc
							(start 0.2794 -0.1778)
							(mid 0.249642 -0.249642)
							(end 0.1778 -0.2794)
						)
					)
					(width 0)
					(fill yes)
				)
			)
		)
	)
	(footprint ""
		(layer "F.Cu")
		(at 207.137 -4.7752 180)
		(property "Reference" "R58"
			(at 0 0 180)
			(layer "F.SilkS")
			(hide yes)
			(effects
				(font
					(size 1.27 1.27)
				)
			)
		)
		(property "Value" "4K7R2F-GP"
			(at 0.064008 -3.993896 180)
			(unlocked yes)
			(layer "F.Fab")
			(hide yes)
			(effects
				(font
					(size 1.016 1.016)
					(thickness 0.1524)
				)
			)
		)
		(property "Device Type" "R402H16"
			(at 0.064008 -5.517896 180)
			(unlocked yes)
			(layer "F.Fab")
			(hide yes)
			(effects
				(font
					(size 1.016 1.016)
					(thickness 0.1524)
				)
			)
		)
		(duplicate_pad_numbers_are_jumpers no)
		(fp_line
			(start 0.508 -0.9398)
			(end -0.508 -0.9398)
			(stroke
				(width 0.1524)
				(type default)
			)
			(layer "F.SilkS")
		)
		(fp_line
			(start -0.508 -0.9398)
			(end -0.508 0.9398)
			(stroke
				(width 0.1524)
				(type default)
			)
			(layer "F.SilkS")
		)
		(fp_rect
			(start -0.508 0.9398)
			(end 0.508 -0.9398)
			(stroke
				(width 0)
				(type default)
			)
			(fill no)
			(layer "F.CrtYd")
		)
		(fp_rect
			(start -0.508 0.9398)
			(end 0.508 -0.9398)
			(stroke
				(width 0)
				(type default)
			)
			(fill no)
			(layer "F.Fab")
		)
		(pad "1" smd custom
			(at 0 -0.4445 180)
			(size 0.1397 0.1397)
			(layers "F.Cu" "F.Mask" "F.Paste")
			(net "DUT_VDDO")
			(options
				(clearance outline)
				(anchor circle)
			)
			(primitives
				(gr_poly
					(pts
						(arc
							(start -0.1778 -0.2794)
							(mid -0.249642 -0.249642)
							(end -0.2794 -0.1778)
						)
						(arc
							(start -0.2794 0.1778)
							(mid -0.249642 0.249642)
							(end -0.1778 0.2794)
						)
						(arc
							(start 0.1778 0.2794)
							(mid 0.249642 0.249642)
							(end 0.2794 0.1778)
						)
						(arc
							(start 0.2794 -0.1778)
							(mid 0.249642 -0.249642)
							(end 0.1778 -0.2794)
						)
					)
					(width 0)
					(fill yes)
				)
			)
		)
		(pad "2" smd custom
			(at 0 0.4445 180)
			(size 0.1397 0.1397)
			(layers "F.Cu" "F.Mask" "F.Paste")
			(net "BOOT_RECOVERY_1")
			(options
				(clearance outline)
				(anchor circle)
			)
			(primitives
				(gr_poly
					(pts
						(arc
							(start -0.1778 -0.2794)
							(mid -0.249642 -0.249642)
							(end -0.2794 -0.1778)
						)
						(arc
							(start -0.2794 0.1778)
							(mid -0.249642 0.249642)
							(end -0.1778 0.2794)
						)
						(arc
							(start 0.1778 0.2794)
							(mid 0.249642 0.249642)
							(end 0.2794 0.1778)
						)
						(arc
							(start 0.2794 -0.1778)
							(mid 0.249642 -0.249642)
							(end 0.1778 -0.2794)
						)
					)
					(width 0)
					(fill yes)
				)
			)
		)
	)
	(footprint ""
		(layer "F.Cu")
		(at 10.9982 -81.6356 90)
		(property "Reference" "R399"
			(at 0 0 90)
			(layer "F.SilkS")
			(hide yes)
			(effects
				(font
					(size 1.27 1.27)
				)
			)
		)
		(property "Value" "10KR2F-2-GP"
			(at 0.064008 -3.993896 90)
			(unlocked yes)
			(layer "F.Fab")
			(hide yes)
			(effects
				(font
					(size 1.016 1.016)
					(thickness 0.1524)
				)
			)
		)
		(property "Device Type" "R402H16"
			(at 0.064008 -5.517896 90)
			(unlocked yes)
			(layer "F.Fab")
			(hide yes)
			(effects
				(font
					(size 1.016 1.016)
					(thickness 0.1524)
				)
			)
		)
		(duplicate_pad_numbers_are_jumpers no)
		(fp_line
			(start 0.508 -0.9398)
			(end -0.508 -0.9398)
			(stroke
				(width 0.1524)
				(type default)
			)
			(layer "F.SilkS")
		)
		(fp_line
			(start -0.508 -0.9398)
			(end -0.508 0.9398)
			(stroke
				(width 0.1524)
				(type default)
			)
			(layer "F.SilkS")
		)
		(fp_rect
			(start -0.508 0.9398)
			(end 0.508 -0.9398)
			(stroke
				(width 0)
				(type default)
			)
			(fill no)
			(layer "F.CrtYd")
		)
		(fp_rect
			(start -0.508 0.9398)
			(end 0.508 -0.9398)
			(stroke
				(width 0)
				(type default)
			)
			(fill no)
			(layer "F.Fab")
		)
		(pad "1" smd custom
			(at 0 -0.4445 90)
			(size 0.1397 0.1397)
			(layers "F.Cu" "F.Mask" "F.Paste")
			(net "P3V3_STBY")
			(options
				(clearance outline)
				(anchor circle)
			)
			(primitives
				(gr_poly
					(pts
						(arc
							(start -0.1778 -0.2794)
							(mid -0.249642 -0.249642)
							(end -0.2794 -0.1778)
						)
						(arc
							(start -0.2794 0.1778)
							(mid -0.249642 0.249642)
							(end -0.1778 0.2794)
						)
						(arc
							(start 0.1778 0.2794)
							(mid 0.249642 0.249642)
							(end 0.2794 0.1778)
						)
						(arc
							(start 0.2794 -0.1778)
							(mid 0.249642 -0.249642)
							(end 0.1778 -0.2794)
						)
					)
					(width 0)
					(fill yes)
				)
			)
		)
		(pad "2" smd custom
			(at 0 0.4445 90)
			(size 0.1397 0.1397)
			(layers "F.Cu" "F.Mask" "F.Paste")
			(net "FM_OSC_50M_EN")
			(options
				(clearance outline)
				(anchor circle)
			)
			(primitives
				(gr_poly
					(pts
						(arc
							(start -0.1778 -0.2794)
							(mid -0.249642 -0.249642)
							(end -0.2794 -0.1778)
						)
						(arc
							(start -0.2794 0.1778)
							(mid -0.249642 0.249642)
							(end -0.1778 0.2794)
						)
						(arc
							(start 0.1778 0.2794)
							(mid 0.249642 0.249642)
							(end 0.2794 0.1778)
						)
						(arc
							(start 0.2794 -0.1778)
							(mid 0.249642 -0.249642)
							(end 0.1778 -0.2794)
						)
					)
					(width 0)
					(fill yes)
				)
			)
		)
	)
	(footprint ""
		(layer "F.Cu")
		(at 159.429704 -33.528)
		(property "Reference" "C399"
			(at 0 0 0)
			(layer "F.SilkS")
			(hide yes)
			(effects
				(font
					(size 1.27 1.27)
				)
			)
		)
		(property "Value" "SCD22U10V2KX-1GP"
			(at 1.1811 -2.7051 0)
			(unlocked yes)
			(layer "F.Fab")
			(hide yes)
			(effects
				(font
					(size 1.016 1.016)
					(thickness 0.1524)
				)
			)
		)
		(property "Device Type" "C402H22"
			(at 1.1811 -4.2291 0)
			(unlocked yes)
			(layer "F.Fab")
			(hide yes)
			(effects
				(font
					(size 1.016 1.016)
					(thickness 0.1524)
				)
			)
		)
		(duplicate_pad_numbers_are_jumpers no)
		(fp_rect
			(start -0.4318 0.9525)
			(end 0.4318 -0.9525)
			(stroke
				(width 0)
				(type default)
			)
			(fill no)
			(layer "F.CrtYd")
		)
		(fp_rect
			(start -0.4318 0.9525)
			(end 0.4318 -0.9525)
			(stroke
				(width 0)
				(type default)
			)
			(fill no)
			(layer "F.Fab")
		)
		(pad "1" smd custom
			(at 0 -0.4445)
			(size 0.1524 0.1524)
			(layers "F.Cu" "F.Mask" "F.Paste")
			(net "PCIE_TX_CAP_N89")
			(options
				(clearance outline)
				(anchor circle)
			)
			(primitives
				(gr_poly
					(pts
						(arc
							(start 0.3048 -0.2032)
							(mid 0.275042 -0.275042)
							(end 0.2032 -0.3048)
						)
						(arc
							(start -0.2032 -0.3048)
							(mid -0.275042 -0.275042)
							(end -0.3048 -0.2032)
						)
						(arc
							(start -0.3048 0.2032)
							(mid -0.275042 0.275042)
							(end -0.2032 0.3048)
						)
						(arc
							(start 0.2032 0.3048)
							(mid 0.275042 0.275042)
							(end 0.3048 0.2032)
						)
					)
					(width 0)
					(fill yes)
				)
			)
		)
		(pad "2" smd custom
			(at 0 0.4445)
			(size 0.1524 0.1524)
			(layers "F.Cu" "F.Mask" "F.Paste")
			(net "PCIE_TX_N89")
			(options
				(clearance outline)
				(anchor circle)
			)
			(primitives
				(gr_poly
					(pts
						(arc
							(start 0.3048 -0.2032)
							(mid 0.275042 -0.275042)
							(end 0.2032 -0.3048)
						)
						(arc
							(start -0.2032 -0.3048)
							(mid -0.275042 -0.275042)
							(end -0.3048 -0.2032)
						)
						(arc
							(start -0.3048 0.2032)
							(mid -0.275042 0.275042)
							(end -0.2032 0.3048)
						)
						(arc
							(start 0.2032 0.3048)
							(mid 0.275042 0.275042)
							(end 0.3048 0.2032)
						)
					)
					(width 0)
					(fill yes)
				)
			)
		)
	)
	(footprint ""
		(layer "F.Cu")
		(at 292.227 -57.15 180)
		(property "Reference" "Q39"
			(at 0 0 180)
			(layer "F.SilkS")
			(hide yes)
			(effects
				(font
					(size 1.27 1.27)
				)
			)
		)
		(property "Value" "2N7002K-1-GP"
			(at 0.127 -8.9662 180)
			(unlocked yes)
			(layer "F.Fab")
			(hide yes)
			(effects
				(font
					(size 1.016 1.016)
					(thickness 0.1524)
				)
			)
		)
		(property "Device Type" "SOT23DGS2D4H44"
			(at 0.127 -10.4902 180)
			(unlocked yes)
			(layer "F.Fab")
			(hide yes)
			(effects
				(font
					(size 1.016 1.016)
					(thickness 0.1524)
				)
			)
		)
		(duplicate_pad_numbers_are_jumpers no)
		(fp_line
			(start 1.651 1.778)
			(end 1.651 -1.778)
			(stroke
				(width 0.1524)
				(type default)
			)
			(layer "F.SilkS")
		)
		(fp_line
			(start 1.651 -1.778)
			(end -1.651 -1.778)
			(stroke
				(width 0.1524)
				(type default)
			)
			(layer "F.SilkS")
		)
		(fp_line
			(start -1.651 1.778)
			(end 1.651 1.778)
			(stroke
				(width 0.1524)
				(type default)
			)
			(layer "F.SilkS")
		)
		(fp_line
			(start -1.651 -1.778)
			(end -1.651 1.778)
			(stroke
				(width 0.1524)
				(type default)
			)
			(layer "F.SilkS")
		)
		(fp_poly
			(pts
				(xy -1.778 1.8796) (xy -1.778 -1.8796) (xy 1.778 -1.8796) (xy 1.778 1.8796)
			)
			(stroke
				(width 0)
				(type default)
			)
			(fill no)
			(layer "F.CrtYd")
		)
		(fp_poly
			(pts
				(xy -1.778 1.8796) (xy -1.778 -1.8796) (xy 1.778 -1.8796) (xy 1.778 1.8796)
			)
			(stroke
				(width 0)
				(type default)
			)
			(fill no)
			(layer "F.Fab")
		)
		(pad "D" smd custom
			(at 0 -0.9525 180)
			(size 0.1905 0.1905)
			(layers "F.Cu" "F.Mask" "F.Paste")
			(net "LED_Q_14")
			(options
				(clearance outline)
				(anchor circle)
			)
			(primitives
				(gr_poly
					(pts
						(arc
							(start -0.1778 0.5715)
							(mid -0.321484 0.511984)
							(end -0.381 0.3683)
						)
						(arc
							(start -0.381 -0.3683)
							(mid -0.321484 -0.511984)
							(end -0.1778 -0.5715)
						)
						(arc
							(start 0.1778 -0.5715)
							(mid 0.321484 -0.511984)
							(end 0.381 -0.3683)
						)
						(arc
							(start 0.381 0.3683)
							(mid 0.321484 0.511984)
							(end 0.1778 0.5715)
						)
					)
					(width 0)
					(fill yes)
				)
			)
		)
		(pad "G" smd custom
			(at -0.98425 0.9525 180)
			(size 0.1905 0.1905)
			(layers "F.Cu" "F.Mask" "F.Paste")
			(net "VS6_LED_R")
			(options
				(clearance outline)
				(anchor circle)
			)
			(primitives
				(gr_poly
					(pts
						(arc
							(start -0.1778 0.5715)
							(mid -0.321484 0.511984)
							(end -0.381 0.3683)
						)
						(arc
							(start -0.381 -0.3683)
							(mid -0.321484 -0.511984)
							(end -0.1778 -0.5715)
						)
						(arc
							(start 0.1778 -0.5715)
							(mid 0.321484 -0.511984)
							(end 0.381 -0.3683)
						)
						(arc
							(start 0.381 0.3683)
							(mid 0.321484 0.511984)
							(end 0.1778 0.5715)
						)
					)
					(width 0)
					(fill yes)
				)
			)
		)
		(pad "S" smd custom
			(at 0.98425 0.9525 180)
			(size 0.1905 0.1905)
			(layers "F.Cu" "F.Mask" "F.Paste")
			(net "GND")
			(options
				(clearance outline)
				(anchor circle)
			)
			(primitives
				(gr_poly
					(pts
						(arc
							(start -0.1778 0.5715)
							(mid -0.321484 0.511984)
							(end -0.381 0.3683)
						)
						(arc
							(start -0.381 -0.3683)
							(mid -0.321484 -0.511984)
							(end -0.1778 -0.5715)
						)
						(arc
							(start 0.1778 -0.5715)
							(mid 0.321484 -0.511984)
							(end 0.381 -0.3683)
						)
						(arc
							(start 0.381 0.3683)
							(mid 0.321484 0.511984)
							(end 0.1778 0.5715)
						)
					)
					(width 0)
					(fill yes)
				)
			)
		)
	)
)
